(kicad_pcb
	(version 20241229)
	(generator "pcbnew")
	(generator_version "9.0")
	(general
		(thickness 1.62)
		(legacy_teardrops no)
	)
	(paper "A4")
	(title_block
		(title "OCuLink to 10GbE adapter")
		(date "2026-02-23")
		(rev "1.1.0")
		(company "Antmicro Ltd")
		(comment 1 "www.antmicro.com")
		(comment 9 "footprints 68-72 of 510")
	)
	(layers
		(0 "F.Cu" signal)
		(4 "In1.Cu" signal)
		(6 "In2.Cu" signal)
		(8 "In3.Cu" signal)
		(10 "In4.Cu" signal)
		(12 "In5.Cu" signal)
		(14 "In6.Cu" signal)
		(2 "B.Cu" signal)
		(9 "F.Adhes" user "F.Adhesive")
		(11 "B.Adhes" user "B.Adhesive")
		(13 "F.Paste" user)
		(15 "B.Paste" user)
		(5 "F.SilkS" user "F.Silkscreen")
		(7 "B.SilkS" user "B.Silkscreen")
		(1 "F.Mask" user)
		(3 "B.Mask" user)
		(17 "Dwgs.User" user "User.Drawings")
		(19 "Cmts.User" user "User.Comments")
		(21 "Eco1.User" user "User.Eco1")
		(23 "Eco2.User" user "User.Eco2")
		(25 "Edge.Cuts" user)
		(27 "Margin" user)
		(31 "F.CrtYd" user "F.Courtyard")
		(29 "B.CrtYd" user "B.Courtyard")
		(35 "F.Fab" user)
		(33 "B.Fab" user)
	)
	(footprint "antmicro-footprints:C_0603_1608Metric_EIA"
		(layer "F.Cu")
		(at 51.9 103.900001 -90)
		(descr "Capacitor SMD 0603, IPC-7351 Density Level A")
		(tags "Capacitor 0603")
		(property "Reference" "C21"
			(at -0.890001 1.56 90)
			(layer "F.SilkS")
			(effects
				(font
					(size 0.7 0.7)
					(thickness 0.15)
				)
				(justify right top)
			)
		)
		(property "Value" "C_22u_16V_0603"
			(at -1.42757 1.770288 90)
			(layer "F.Fab")
			(hide yes)
			(effects
				(font
					(size 0.7 0.7)
					(thickness 0.15)
				)
				(justify right top)
			)
		)
		(property "Datasheet" "https://product.samsungsem.com/mlcc/CL10A226MO7JZN.do"
			(at 0 0 90)
			(layer "F.Fab")
			(hide yes)
			(effects
				(font
					(size 1.27 1.27)
					(thickness 0.15)
				)
			)
		)
		(property "Description" "SMD Multilayer Ceramic Capacitor"
			(at 0 0 90)
			(layer "F.Fab")
			(hide yes)
			(effects
				(font
					(size 1.27 1.27)
					(thickness 0.15)
				)
			)
		)
		(property "MPN" "CL10A226MO7JZNC"
			(at 0 0 270)
			(unlocked yes)
			(layer "F.Fab")
			(hide yes)
			(effects
				(font
					(size 1 1)
					(thickness 0.15)
				)
			)
		)
		(property "Manufacturer" "Samsung Electro-Mechanics"
			(at 0 0 270)
			(unlocked yes)
			(layer "F.Fab")
			(hide yes)
			(effects
				(font
					(size 1 1)
					(thickness 0.15)
				)
			)
		)
		(property "License" "Apache-2.0"
			(at 0 0 270)
			(unlocked yes)
			(layer "F.Fab")
			(hide yes)
			(effects
				(font
					(size 1 1)
					(thickness 0.15)
				)
			)
		)
		(property "Author" "Antmicro"
			(at 0 0 270)
			(unlocked yes)
			(layer "F.Fab")
			(hide yes)
			(effects
				(font
					(size 1 1)
					(thickness 0.15)
				)
			)
		)
		(property "Val" "22u"
			(at 0 0 270)
			(unlocked yes)
			(layer "F.Fab")
			(hide yes)
			(effects
				(font
					(size 1 1)
					(thickness 0.15)
				)
			)
		)
		(property "Voltage" "16V"
			(at 0 0 270)
			(unlocked yes)
			(layer "F.Fab")
			(hide yes)
			(effects
				(font
					(size 1 1)
					(thickness 0.15)
				)
			)
		)
		(property "Dielectric" ""
			(at 0 0 270)
			(unlocked yes)
			(layer "F.Fab")
			(hide yes)
			(effects
				(font
					(size 1 1)
					(thickness 0.15)
				)
			)
		)
		(property "Public" "False"
			(at 0 0 270)
			(unlocked yes)
			(layer "F.Fab")
			(hide yes)
			(effects
				(font
					(size 1 1)
					(thickness 0.15)
				)
			)
		)
		(sheetname "/Power/")
		(sheetfile "power.kicad_sch")
		(attr smd)
		(fp_line
			(start -0.15 0.55)
			(end 0.15 0.55)
			(stroke
				(width 0.15)
				(type solid)
			)
			(layer "F.SilkS")
		)
		(fp_line
			(start -0.15 -0.55)
			(end 0.15 -0.55)
			(stroke
				(width 0.15)
				(type solid)
			)
			(layer "F.SilkS")
		)
		(fp_rect
			(start -1.25 -0.65)
			(end 1.25 0.65)
			(stroke
				(width 0.05)
				(type solid)
			)
			(fill no)
			(layer "F.CrtYd")
		)
		(fp_rect
			(start -0.8 -0.45)
			(end 0.8 0.45)
			(stroke
				(width 0.15)
				(type solid)
			)
			(fill no)
			(layer "F.Fab")
		)
		(pad "1" smd roundrect
			(at -0.7 0 270)
			(size 0.8 1.1)
			(layers "F.Cu" "F.Mask" "F.Paste")
			(roundrect_rratio 0.2)
			(net 28 "GND")
			(pintype "passive")
		)
		(pad "2" smd roundrect
			(at 0.7 0 270)
			(size 0.8 1.1)
			(layers "F.Cu" "F.Mask" "F.Paste")
			(roundrect_rratio 0.2)
			(net 314 "VCC")
			(pintype "passive")
		)
	)
	(footprint "antmicro-footprints:VQFN-HR-9_2x1.5mm"
		(layer "F.Cu")
		(at 56.100001 88.049999 -90)
		(property "Reference" "U2"
			(at 1.290001 0.380001 180)
			(layer "F.SilkS")
			(effects
				(font
					(size 0.7 0.7)
					(thickness 0.15)
				)
				(justify right top)
			)
		)
		(property "Value" "TPS566231P"
			(at -1.45 2.45 90)
			(layer "F.Fab")
			(hide yes)
			(effects
				(font
					(size 0.7 0.7)
					(thickness 0.15)
				)
				(justify right top)
			)
		)
		(property "Datasheet" "https://www.ti.com/lit/ds/symlink/tps566231.pdf"
			(at 0 -0.045 90)
			(layer "F.Fab")
			(hide yes)
			(effects
				(font
					(size 0.7 0.7)
					(thickness 0.15)
				)
				(justify right top)
			)
		)
		(property "Description" "Switching Voltage Regulators 3-V to 18-V, 6-A synchronous buck converter"
			(at -1.45 3.65 90)
			(layer "F.Fab")
			(hide yes)
			(effects
				(font
					(size 0.7 0.7)
					(thickness 0.15)
				)
				(justify right top)
			)
		)
		(property "Manufacturer" "Texas Instruments"
			(at 0 0 270)
			(unlocked yes)
			(layer "F.Fab")
			(hide yes)
			(effects
				(font
					(size 1 1)
					(thickness 0.15)
				)
			)
		)
		(property "MPN" "TPS566231PRQFR"
			(at 0 0 270)
			(unlocked yes)
			(layer "F.Fab")
			(hide yes)
			(effects
				(font
					(size 1 1)
					(thickness 0.15)
				)
			)
		)
		(property "Author" "Antmicro"
			(at 0 0 270)
			(unlocked yes)
			(layer "F.Fab")
			(hide yes)
			(effects
				(font
					(size 1 1)
					(thickness 0.15)
				)
			)
		)
		(property "License" "Apache-2.0"
			(at 0 0 270)
			(unlocked yes)
			(layer "F.Fab")
			(hide yes)
			(effects
				(font
					(size 1 1)
					(thickness 0.15)
				)
			)
		)
		(sheetname "/Power/")
		(sheetfile "power.kicad_sch")
		(attr smd)
		(fp_line
			(start -1 0.945)
			(end -0.695 0.945)
			(stroke
				(width 0.15)
				(type solid)
			)
			(layer "F.SilkS")
		)
		(fp_line
			(start 1 0.945)
			(end 0.2 0.945)
			(stroke
				(width 0.15)
				(type solid)
			)
			(layer "F.SilkS")
		)
		(fp_line
			(start -1 -0.945)
			(end -0.695 -0.945)
			(stroke
				(width 0.15)
				(type solid)
			)
			(layer "F.SilkS")
		)
		(fp_line
			(start 1 -0.945)
			(end 0.695 -0.945)
			(stroke
				(width 0.15)
				(type solid)
			)
			(layer "F.SilkS")
		)
		(fp_circle
			(center -1.18 -0.77)
			(end -1.13 -0.77)
			(stroke
				(width 0.15)
				(type solid)
			)
			(fill yes)
			(layer "F.SilkS")
		)
		(fp_rect
			(start -1.3 -1.05)
			(end 1.3 1.05)
			(stroke
				(width 0.05)
				(type solid)
			)
			(fill no)
			(layer "F.CrtYd")
		)
		(fp_rect
			(start -1 -0.75)
			(end 1 0.75)
			(stroke
				(width 0.15)
				(type solid)
			)
			(fill no)
			(layer "F.Fab")
		)
		(pad "1" smd roundrect
			(at -0.925 -0.5 270)
			(size 0.55 0.25)
			(layers "F.Cu" "F.Mask" "F.Paste")
			(roundrect_rratio 0.125)
			(net 322 "/Power/VCCD_VCC")
			(pinfunction "V_{CC}")
			(pintype "passive")
		)
		(pad "2" smd roundrect
			(at -0.925 0 270)
			(size 0.55 0.25)
			(layers "F.Cu" "F.Mask" "F.Paste")
			(roundrect_rratio 0.125)
			(net 329 "/Power/VCCD_FB")
			(pinfunction "FB")
			(pintype "input")
		)
		(pad "3" smd roundrect
			(at -0.925 0.5 270)
			(size 0.55 0.25)
			(layers "F.Cu" "F.Mask" "F.Paste")
			(roundrect_rratio 0.125)
			(net 340 "/Power/VCCD_EN")
			(pinfunction "EN")
			(pintype "input")
		)
		(pad "4" smd roundrect
			(at -0.25 0.45 270)
			(size 0.25 1)
			(layers "F.Cu" "F.Mask" "F.Paste")
			(roundrect_rratio 0.125)
			(net 28 "GND")
			(pinfunction "PGND")
			(pintype "power_in")
		)
		(pad "5" smd roundrect
			(at 0.925 0.5 270)
			(size 0.55 0.25)
			(layers "F.Cu" "F.Mask" "F.Paste")
			(roundrect_rratio 0.125)
			(net 314 "VCC")
			(pinfunction "V_{IN}")
			(pintype "power_in")
		)
		(pad "6" smd roundrect
			(at 0.925 0 270)
			(size 0.55 0.25)
			(layers "F.Cu" "F.Mask" "F.Paste")
			(roundrect_rratio 0.125)
			(net 314 "VCC")
			(pinfunction "V_{IN}")
			(pintype "passive")
		)
		(pad "7" smd roundrect
			(at 0.925 -0.5 270)
			(size 0.55 0.25)
			(layers "F.Cu" "F.Mask" "F.Paste")
			(roundrect_rratio 0.125)
			(net 318 "/Power/VCCD_BST")
			(pinfunction "BST")
			(pintype "passive")
		)
		(pad "8" smd roundrect
			(at 0.25 -0.3 270)
			(size 0.25 1.3)
			(layers "F.Cu" "F.Mask" "F.Paste")
			(roundrect_rratio 0.125)
			(net 334 "/Power/VCCD_SW")
			(pinfunction "SW")
			(pintype "power_out")
		)
		(pad "9" smd roundrect
			(at -0.25 -0.675 270)
			(size 0.25 0.55)
			(layers "F.Cu" "F.Mask" "F.Paste")
			(roundrect_rratio 0.125)
			(net 342 "/Power/VCCD_PG")
			(pinfunction "PG")
			(pintype "passive")
		)
	)
	(footprint "antmicro-footprints:R_0402_1005Metric"
		(layer "F.Cu")
		(at 56.97 82.764 -90)
		(descr "Resistor SMD 0402")
		(tags "resistor SMD 0402")
		(property "Reference" "R53"
			(at -3.094 0.09 90)
			(layer "F.SilkS")
			(effects
				(font
					(size 0.7 0.7)
					(thickness 0.15)
				)
				(justify right top)
			)
		)
		(property "Value" "R_8k2_0402"
			(at -1.011843 1.772046 90)
			(layer "F.Fab")
			(hide yes)
			(effects
				(font
					(size 0.7 0.7)
					(thickness 0.15)
				)
				(justify right top)
			)
		)
		(property "Datasheet" "https://www.bourns.com/docs/product-datasheets/cr.pdf"
			(at 0 0 90)
			(layer "F.Fab")
			(hide yes)
			(effects
				(font
					(size 1.27 1.27)
					(thickness 0.15)
				)
			)
		)
		(property "Description" "SMD Chip Resistor"
			(at 0 0 90)
			(layer "F.Fab")
			(hide yes)
			(effects
				(font
					(size 1.27 1.27)
					(thickness 0.15)
				)
			)
		)
		(property "MPN" "CR0402-FX-8201GLF"
			(at 0 0 270)
			(unlocked yes)
			(layer "F.Fab")
			(hide yes)
			(effects
				(font
					(size 1 1)
					(thickness 0.15)
				)
			)
		)
		(property "Manufacturer" "Bourns"
			(at 0 0 270)
			(unlocked yes)
			(layer "F.Fab")
			(hide yes)
			(effects
				(font
					(size 1 1)
					(thickness 0.15)
				)
			)
		)
		(property "License" "Apache-2.0"
			(at 0 0 270)
			(unlocked yes)
			(layer "F.Fab")
			(hide yes)
			(effects
				(font
					(size 1 1)
					(thickness 0.15)
				)
			)
		)
		(property "Author" "Antmicro"
			(at 0 0 270)
			(unlocked yes)
			(layer "F.Fab")
			(hide yes)
			(effects
				(font
					(size 1 1)
					(thickness 0.15)
				)
			)
		)
		(property "Val" "8k2"
			(at 0 0 270)
			(unlocked yes)
			(layer "F.Fab")
			(hide yes)
			(effects
				(font
					(size 1 1)
					(thickness 0.15)
				)
			)
		)
		(property "Tolerance" "1%"
			(at 0 0 270)
			(unlocked yes)
			(layer "F.Fab")
			(hide yes)
			(effects
				(font
					(size 1 1)
					(thickness 0.15)
				)
			)
		)
		(sheetname "/X710-AT2 PCIe/")
		(sheetfile "x710-at2-pcie.kicad_sch")
		(attr smd)
		(fp_rect
			(start -0.925 -0.47)
			(end 0.925 0.47)
			(stroke
				(width 0.05)
				(type default)
			)
			(fill no)
			(layer "F.CrtYd")
		)
		(fp_rect
			(start -0.5 -0.25)
			(end 0.5 0.25)
			(stroke
				(width 0.15)
				(type solid)
			)
			(fill no)
			(layer "F.Fab")
		)
		(pad "1" smd roundrect
			(at -0.48 0 270)
			(size 0.59 0.64)
			(layers "F.Cu" "F.Mask" "F.Paste")
			(roundrect_rratio 0.25)
			(net 4 "/X710-AT2 PCIe/PCIe_JTAG.JTMS")
			(pintype "passive")
		)
		(pad "2" smd roundrect
			(at 0.48 0 270)
			(size 0.59 0.64)
			(layers "F.Cu" "F.Mask" "F.Paste")
			(roundrect_rratio 0.25)
			(net 7 "+3V3")
			(pintype "passive")
		)
	)
	(footprint "antmicro-footprints:C_0402_1005Metric"
		(layer "F.Cu")
		(at 55.099999 92.849999 90)
		(descr "Capacitor SMD 0402")
		(tags "capacitor SMD 0402")
		(property "Reference" "C39"
			(at -1.120001 -2.329999 90)
			(layer "F.SilkS")
			(effects
				(font
					(size 0.7 0.7)
					(thickness 0.15)
				)
				(justify left bottom)
			)
		)
		(property "Value" "C_33p_0402"
			(at -1.022927 2.155213 90)
			(layer "F.Fab")
			(hide yes)
			(effects
				(font
					(size 0.7 0.7)
					(thickness 0.15)
				)
				(justify left bottom)
			)
		)
		(property "Datasheet" "https://spicat.kyocera-avx.com/product/mlcc/chartview/04025A330FAT2A/"
			(at 0 0 90)
			(layer "F.Fab")
			(hide yes)
			(effects
				(font
					(size 1.27 1.27)
					(thickness 0.15)
				)
			)
		)
		(property "Description" "SMD Multilayer Ceramic Capacitor, 33 pF, 50 V, 0402 [1005 Metric], ± 5%, C0G / NP0, MC"
			(at 0 0 90)
			(layer "F.Fab")
			(hide yes)
			(effects
				(font
					(size 1.27 1.27)
					(thickness 0.15)
				)
			)
		)
		(property "MPN" "04025A330FAT2A"
			(at 0 0 90)
			(unlocked yes)
			(layer "F.Fab")
			(hide yes)
			(effects
				(font
					(size 1 1)
					(thickness 0.15)
				)
			)
		)
		(property "Manufacturer" "KYOCERA AVX"
			(at 0 0 90)
			(unlocked yes)
			(layer "F.Fab")
			(hide yes)
			(effects
				(font
					(size 1 1)
					(thickness 0.15)
				)
			)
		)
		(property "License" "Apache-2.0"
			(at 0 0 90)
			(unlocked yes)
			(layer "F.Fab")
			(hide yes)
			(effects
				(font
					(size 1 1)
					(thickness 0.15)
				)
			)
		)
		(property "Author" "Antmicro"
			(at 0 0 90)
			(unlocked yes)
			(layer "F.Fab")
			(hide yes)
			(effects
				(font
					(size 1 1)
					(thickness 0.15)
				)
			)
		)
		(property "Val" "33p"
			(at 0 0 90)
			(unlocked yes)
			(layer "F.Fab")
			(hide yes)
			(effects
				(font
					(size 1 1)
					(thickness 0.15)
				)
			)
		)
		(property "Voltage" ""
			(at 0 0 90)
			(unlocked yes)
			(layer "F.Fab")
			(hide yes)
			(effects
				(font
					(size 1 1)
					(thickness 0.15)
				)
			)
		)
		(property "Dielectric" ""
			(at 0 0 90)
			(unlocked yes)
			(layer "F.Fab")
			(hide yes)
			(effects
				(font
					(size 1 1)
					(thickness 0.15)
				)
			)
		)
		(sheetname "/Power/")
		(sheetfile "power.kicad_sch")
		(attr smd exclude_from_pos_files exclude_from_bom dnp)
		(fp_rect
			(start -0.925 -0.47)
			(end 0.925 0.47)
			(stroke
				(width 0.05)
				(type default)
			)
			(fill no)
			(layer "F.CrtYd")
		)
		(fp_line
			(start 0.504 -0.25)
			(end 0.504 0.248)
			(stroke
				(width 0.15)
				(type solid)
			)
			(layer "F.Fab")
		)
		(fp_line
			(start -0.494 -0.25)
			(end 0.504 -0.25)
			(stroke
				(width 0.15)
				(type solid)
			)
			(layer "F.Fab")
		)
		(fp_line
			(start 0.504 0.248)
			(end -0.494 0.248)
			(stroke
				(width 0.15)
				(type solid)
			)
			(layer "F.Fab")
		)
		(fp_line
			(start -0.494 0.248)
			(end -0.494 -0.25)
			(stroke
				(width 0.15)
				(type solid)
			)
			(layer "F.Fab")
		)
		(pad "1" smd roundrect
			(at -0.48 0 90)
			(size 0.59 0.64)
			(layers "F.Cu" "F.Mask" "F.Paste")
			(roundrect_rratio 0.25)
			(net 331 "/Power/DVDD_FB")
			(pintype "passive")
		)
		(pad "2" smd roundrect
			(at 0.48 0 90)
			(size 0.59 0.64)
			(layers "F.Cu" "F.Mask" "F.Paste")
			(roundrect_rratio 0.25)
			(net 311 "/Power/+DVDD_OUT")
			(pintype "passive")
		)
	)
	(footprint "antmicro-footprints:C_0603_1608Metric_EIA"
		(layer "F.Cu")
		(at 66.7 90.699999 180)
		(descr "Capacitor SMD 0603, IPC-7351 Density Level A")
		(tags "Capacitor 0603")
		(property "Reference" "C81"
			(at 1.01 1.139999 0)
			(layer "F.SilkS")
			(effects
				(font
					(size 0.7 0.7)
					(thickness 0.15)
				)
				(justify right top)
			)
		)
		(property "Value" "C_22u_16V_0603"
			(at -1.42757 1.770288 0)
			(layer "F.Fab")
			(hide yes)
			(effects
				(font
					(size 0.7 0.7)
					(thickness 0.15)
				)
				(justify right top)
			)
		)
		(property "Datasheet" "https://product.samsungsem.com/mlcc/CL10A226MO7JZN.do"
			(at 0 0 0)
			(layer "F.Fab")
			(hide yes)
			(effects
				(font
					(size 1.27 1.27)
					(thickness 0.15)
				)
			)
		)
		(property "Description" "SMD Multilayer Ceramic Capacitor"
			(at 0 0 0)
			(layer "F.Fab")
			(hide yes)
			(effects
				(font
					(size 1.27 1.27)
					(thickness 0.15)
				)
			)
		)
		(property "MPN" "CL10A226MO7JZNC"
			(at 0 0 180)
			(unlocked yes)
			(layer "F.Fab")
			(hide yes)
			(effects
				(font
					(size 1 1)
					(thickness 0.15)
				)
			)
		)
		(property "Manufacturer" "Samsung Electro-Mechanics"
			(at 0 0 180)
			(unlocked yes)
			(layer "F.Fab")
			(hide yes)
			(effects
				(font
					(size 1 1)
					(thickness 0.15)
				)
			)
		)
		(property "License" "Apache-2.0"
			(at 0 0 180)
			(unlocked yes)
			(layer "F.Fab")
			(hide yes)
			(effects
				(font
					(size 1 1)
					(thickness 0.15)
				)
			)
		)
		(property "Author" "Antmicro"
			(at 0 0 180)
			(unlocked yes)
			(layer "F.Fab")
			(hide yes)
			(effects
				(font
					(size 1 1)
					(thickness 0.15)
				)
			)
		)
		(property "Val" "22u"
			(at 0 0 180)
			(unlocked yes)
			(layer "F.Fab")
			(hide yes)
			(effects
				(font
					(size 1 1)
					(thickness 0.15)
				)
			)
		)
		(property "Voltage" "16V"
			(at 0 0 180)
			(unlocked yes)
			(layer "F.Fab")
			(hide yes)
			(effects
				(font
					(size 1 1)
					(thickness 0.15)
				)
			)
		)
		(property "Dielectric" ""
			(at 0 0 180)
			(unlocked yes)
			(layer "F.Fab")
			(hide yes)
			(effects
				(font
					(size 1 1)
					(thickness 0.15)
				)
			)
		)
		(sheetname "/X710-AT2 power/")
		(sheetfile "x710-at2-power.kicad_sch")
		(attr smd)
		(fp_line
			(start -0.15 0.55)
			(end 0.15 0.55)
			(stroke
				(width 0.15)
				(type solid)
			)
			(layer "F.SilkS")
		)
		(fp_line
			(start -0.15 -0.55)
			(end 0.15 -0.55)
			(stroke
				(width 0.15)
				(type solid)
			)
			(layer "F.SilkS")
		)
		(fp_rect
			(start -1.25 -0.65)
			(end 1.25 0.65)
			(stroke
				(width 0.05)
				(type solid)
			)
			(fill no)
			(layer "F.CrtYd")
		)
		(fp_rect
			(start -0.8 -0.45)
			(end 0.8 0.45)
			(stroke
				(width 0.15)
				(type solid)
			)
			(fill no)
			(layer "F.Fab")
		)
		(pad "1" smd roundrect
			(at -0.7 0 180)
			(size 0.8 1.1)
			(layers "F.Cu" "F.Mask" "F.Paste")
			(roundrect_rratio 0.2)
			(net 28 "GND")
			(pintype "passive")
		)
		(pad "2" smd roundrect
			(at 0.7 0 180)
			(size 0.8 1.1)
			(layers "F.Cu" "F.Mask" "F.Paste")
			(roundrect_rratio 0.2)
			(net 6 "DVDD")
			(pintype "passive")
		)
	)
)
